(kicad_pcb
	(version 20241229)
	(generator "pcbnew")
	(generator_version "9.0")
	(general
		(thickness 1.711)
		(legacy_teardrops no)
	)
	(paper "A4")
	(title_block
		(title "Antmicro Baseboard for Jetson AGX Thor")
		(date "2026-02-18")
		(rev "1.1.0")
		(company "Antmicro Ltd")
		(comment 1 "www.antmicro.com")
		(comment 9 "footprints 603-605 of 1170")
	)
	(layers
		(0 "F.Cu" signal)
		(4 "In1.Cu" signal)
		(6 "In2.Cu" signal)
		(8 "In3.Cu" signal)
		(10 "In4.Cu" jumper)
		(12 "In5.Cu" signal)
		(14 "In6.Cu" signal)
		(16 "In7.Cu" signal)
		(18 "In8.Cu" signal)
		(2 "B.Cu" signal)
		(9 "F.Adhes" user "F.Adhesive")
		(11 "B.Adhes" user "B.Adhesive")
		(13 "F.Paste" user)
		(15 "B.Paste" user)
		(5 "F.SilkS" user "F.Silkscreen")
		(7 "B.SilkS" user "B.Silkscreen")
		(1 "F.Mask" user)
		(3 "B.Mask" user)
		(17 "Dwgs.User" user "User.Drawings")
		(19 "Cmts.User" user "User.Comments")
		(21 "Eco1.User" user "User.Eco1")
		(23 "Eco2.User" user "User.Eco2")
		(25 "Edge.Cuts" user)
		(27 "Margin" user)
		(31 "F.CrtYd" user "F.Courtyard")
		(29 "B.CrtYd" user "B.Courtyard")
		(35 "F.Fab" user)
		(33 "B.Fab" user)
	)
	(footprint "antmicro-footprints:R_0402_1005Metric"
		(layer "F.Cu")
		(at 161.729468 78.11 90)
		(descr "Resistor SMD 0402")
		(tags "resistor SMD 0402")
		(property "Reference" "R371"
			(at -1 -1.809468 90)
			(layer "F.SilkS")
			(effects
				(font
					(size 0.7 0.7)
					(thickness 0.15)
				)
				(justify left bottom)
			)
		)
		(property "Value" "R_27R_0402"
			(at -1.011843 1.772047 90)
			(layer "F.Fab")
			(effects
				(font
					(size 0.7 0.7)
					(thickness 0.15)
				)
				(justify left bottom)
			)
		)
		(property "Datasheet" "https://www.bourns.com/docs/product-datasheets/cr.pdf"
			(at 0 0 90)
			(layer "F.Fab")
			(hide yes)
			(effects
				(font
					(size 1.27 1.27)
					(thickness 0.15)
				)
			)
		)
		(property "Description" "SMD Chip Resistor, 27 ohm, ± 1%, 63 mW, 0402 [1005 Metric], Thick Film, General Purpose"
			(at 0 0 90)
			(layer "F.Fab")
			(hide yes)
			(effects
				(font
					(size 1.27 1.27)
					(thickness 0.15)
				)
			)
		)
		(property "Manufacturer" "Bourns"
			(at 0 0 90)
			(unlocked yes)
			(layer "F.Fab")
			(hide yes)
			(effects
				(font
					(size 1 1)
					(thickness 0.15)
				)
			)
		)
		(property "MPN" "CR0402-FX-27R0GLF"
			(at 0 0 90)
			(unlocked yes)
			(layer "F.Fab")
			(hide yes)
			(effects
				(font
					(size 1 1)
					(thickness 0.15)
				)
			)
		)
		(property "Val" "27R"
			(at 0 0 90)
			(unlocked yes)
			(layer "F.Fab")
			(hide yes)
			(effects
				(font
					(size 1 1)
					(thickness 0.15)
				)
			)
		)
		(property "License" "Apache-2.0"
			(at 0 0 90)
			(unlocked yes)
			(layer "F.Fab")
			(hide yes)
			(effects
				(font
					(size 1 1)
					(thickness 0.15)
				)
			)
		)
		(property "Author" "Antmicro"
			(at 0 0 90)
			(unlocked yes)
			(layer "F.Fab")
			(hide yes)
			(effects
				(font
					(size 1 1)
					(thickness 0.15)
				)
			)
		)
		(property "Tolerance" "1%"
			(at 0 0 90)
			(unlocked yes)
			(layer "F.Fab")
			(hide yes)
			(effects
				(font
					(size 1 1)
					(thickness 0.15)
				)
			)
		)
		(component_classes
			(class "DCDC_20V")
		)
		(sheetname "/DCDC/")
		(sheetfile "dcdc.kicad_sch")
		(attr smd)
		(fp_rect
			(start -0.925 -0.47)
			(end 0.925 0.47)
			(stroke
				(width 0.05)
				(type default)
			)
			(fill no)
			(layer "F.CrtYd")
		)
		(fp_rect
			(start -0.5 -0.25)
			(end 0.5 0.25)
			(stroke
				(width 0.15)
				(type solid)
			)
			(fill no)
			(layer "F.Fab")
		)
		(fp_text user "${REFERENCE}"
			(at -0.95 3.168 90)
			(layer "F.Fab")
			(effects
				(font
					(size 0.7 0.7)
					(thickness 0.15)
				)
				(justify left bottom)
			)
		)
		(fp_text user "Author: Antmicro"
			(at -0.95 4.169 90)
			(layer "F.Fab")
			(effects
				(font
					(size 0.7 0.7)
					(thickness 0.15)
				)
				(justify left bottom)
			)
		)
		(fp_text user "License: Apache-2.0"
			(at -0.95 5.169 90)
			(layer "F.Fab")
			(effects
				(font
					(size 0.7 0.7)
					(thickness 0.15)
				)
				(justify left bottom)
			)
		)
		(pad "1" smd roundrect
			(at -0.48 0 90)
			(size 0.59 0.64)
			(layers "F.Cu" "F.Mask" "F.Paste")
			(roundrect_rratio 0.25)
			(net 1221 "Net-(U66-IN-)")
			(pintype "passive")
		)
		(pad "2" smd roundrect
			(at 0.48 0 90)
			(size 0.59 0.64)
			(layers "F.Cu" "F.Mask" "F.Paste")
			(roundrect_rratio 0.25)
			(net 904 "+20V")
			(pintype "passive")
		)
	)
	(footprint "antmicro-footprints:USB-C_Receptacle_Kycon_KUSBX-SL2-CS1N24-B-TR"
		(locked yes)
		(layer "F.Cu")
		(at 236.455532 115.21 90)
		(descr "USB-C (USB TYPE-C) USB 3.2 Gen 2 (USB 3.1 Gen 2, Superspeed + (USB 3.1)) Receptacle Connector 24 Position Through Hole, Right Angle")
		(tags "CONNECTOR, USB")
		(property "Reference" "J6"
			(at 3.11 -10.685532 180)
			(layer "F.SilkS")
			(effects
				(font
					(size 0.7 0.7)
					(thickness 0.15)
				)
				(justify left bottom)
			)
		)
		(property "Value" "USB-C_Kycon_KUSBX-SL2-CS1N24-B-TR"
			(at 0 7.5 90)
			(layer "F.Fab")
			(effects
				(font
					(size 0.7 0.7)
					(thickness 0.15)
				)
				(justify right top)
			)
		)
		(property "Datasheet" "https://www.kycon.com/Pub_Eng_Draw/KUSBX-SL2-CS1N24-B-TR.pdf"
			(at 0 0 90)
			(layer "F.Fab")
			(hide yes)
			(effects
				(font
					(size 1.27 1.27)
					(thickness 0.15)
				)
			)
		)
		(property "Description" "USB-C (USB TYPE-C) USB 3.2 Gen 2 (USB 3.1 Gen 2, Superspeed + (USB 3.1)) USB PD Receptacle Connector 24 Position Surface Mount"
			(at 0 0 90)
			(layer "F.Fab")
			(hide yes)
			(effects
				(font
					(size 1.27 1.27)
					(thickness 0.15)
				)
			)
		)
		(property "MPN" "KUSBX-SL2-CS1N24-B-TR"
			(at 0 0 90)
			(unlocked yes)
			(layer "F.Fab")
			(hide yes)
			(effects
				(font
					(size 1 1)
					(thickness 0.15)
				)
			)
		)
		(property "Manufacturer" "Kycon"
			(at 0 0 90)
			(unlocked yes)
			(layer "F.Fab")
			(hide yes)
			(effects
				(font
					(size 1 1)
					(thickness 0.15)
				)
			)
		)
		(property "License" "Apache-2.0"
			(at 0 0 90)
			(unlocked yes)
			(layer "F.Fab")
			(hide yes)
			(effects
				(font
					(size 1 1)
					(thickness 0.15)
				)
			)
		)
		(property "Author" "Antmicro"
			(at 0 0 90)
			(unlocked yes)
			(layer "F.Fab")
			(hide yes)
			(effects
				(font
					(size 1 1)
					(thickness 0.15)
				)
			)
		)
		(sheetname "/USB Hub/")
		(sheetfile "usb_hub.kicad_sch")
		(attr smd)
		(fp_line
			(start 1 -8.8)
			(end 1 -8.8)
			(stroke
				(width 0.15)
				(type solid)
			)
			(layer "F.SilkS")
		)
		(fp_line
			(start 1 -8.8)
			(end -1 -8.8)
			(stroke
				(width 0.15)
				(type solid)
			)
			(layer "F.SilkS")
		)
		(fp_line
			(start -1 -8.8)
			(end 1 -8.8)
			(stroke
				(width 0.15)
				(type solid)
			)
			(layer "F.SilkS")
		)
		(fp_line
			(start -1 -8.8)
			(end -1 -8.8)
			(stroke
				(width 0.15)
				(type solid)
			)
			(layer "F.SilkS")
		)
		(fp_rect
			(start -4 -9.4)
			(end 4 5.65)
			(stroke
				(width 0.05)
				(type solid)
			)
			(fill no)
			(layer "F.CrtYd")
		)
		(fp_line
			(start 2.25 -8.8)
			(end -2.25 -8.8)
			(stroke
				(width 0.15)
				(type solid)
			)
			(layer "F.Fab")
		)
		(fp_line
			(start -2.25 -8.8)
			(end -2.25 5.5)
			(stroke
				(width 0.15)
				(type solid)
			)
			(layer "F.Fab")
		)
		(fp_line
			(start 2.25 5.5)
			(end 2.25 -8.8)
			(stroke
				(width 0.15)
				(type solid)
			)
			(layer "F.Fab")
		)
		(fp_line
			(start -2.25 5.5)
			(end 2.25 5.5)
			(stroke
				(width 0.15)
				(type solid)
			)
			(layer "F.Fab")
		)
		(fp_text user "Author: Antmicro"
			(at -5.47 9.7 90)
			(layer "F.Fab")
			(effects
				(font
					(size 0.7 0.7)
					(thickness 0.15)
				)
				(justify left bottom)
			)
		)
		(fp_text user "License: Apache-2.0"
			(at -5.47 10.9 90)
			(layer "F.Fab")
			(effects
				(font
					(size 0.7 0.7)
					(thickness 0.15)
				)
				(justify left bottom)
			)
		)
		(fp_text user "${REFERENCE}"
			(at -5.47 8.5 90)
			(layer "F.Fab")
			(effects
				(font
					(size 0.7 0.7)
					(thickness 0.15)
				)
				(justify left bottom)
			)
		)
		(pad "" np_thru_hole circle
			(at 0 -7.6 90)
			(size 1.1 1.1)
			(drill 1.1)
			(layers "*.Cu" "*.Mask")
		)
		(pad "" np_thru_hole circle
			(at 0 0 90)
			(size 1 1)
			(drill 1)
			(layers "*.Cu" "*.Mask")
		)
		(pad "A1" smd rect
			(at 1.1375 -6.525 180)
			(size 0.25 1.625)
			(layers "F.Cu" "F.Mask" "F.Paste")
			(net 1 "GND")
			(pinfunction "GND")
			(pintype "power_in")
		)
		(pad "A2" smd rect
			(at 1.1375 -6.025 180)
			(size 0.25 1.625)
			(layers "F.Cu" "F.Mask" "F.Paste")
			(net 164 "/USB Hub/USBC3_CONN_TX1_P")
			(pinfunction "TX_{1}+")
			(pintype "bidirectional")
		)
		(pad "A3" smd rect
			(at 1.1375 -5.525 180)
			(size 0.25 1.625)
			(layers "F.Cu" "F.Mask" "F.Paste")
			(net 95 "/USB Hub/USBC3_CONN_TX1_N")
			(pinfunction "TX_{1}-")
			(pintype "bidirectional")
		)
		(pad "A4" smd rect
			(at 1.1375 -5.025 180)
			(size 0.25 1.625)
			(layers "F.Cu" "F.Mask" "F.Paste")
			(net 71 "/USB Hub/USBC3_VBUS")
			(pinfunction "VBUS")
			(pintype "power_in")
		)
		(pad "A5" smd rect
			(at 1.1375 -4.525 180)
			(size 0.25 1.625)
			(layers "F.Cu" "F.Mask" "F.Paste")
			(net 510 "/USB Hub/USBC3_CC_{1}")
			(pinfunction "CC_{1}")
			(pintype "bidirectional")
		)
		(pad "A6" smd rect
			(at 1.1375 -4.025 180)
			(size 0.25 1.625)
			(layers "F.Cu" "F.Mask" "F.Paste")
			(net 506 "/USB Hub/USBC3_D+")
			(pinfunction "D_{A}+")
			(pintype "bidirectional")
		)
		(pad "A7" smd rect
			(at 1.1375 -3.525 180)
			(size 0.25 1.625)
			(layers "F.Cu" "F.Mask" "F.Paste")
			(net 508 "/USB Hub/USBC3_D-")
			(pinfunction "D_{A}-")
			(pintype "bidirectional")
		)
		(pad "A8" smd rect
			(at 1.1375 -3.025 180)
			(size 0.25 1.625)
			(layers "F.Cu" "F.Mask" "F.Paste")
			(net 179 "unconnected-(J6-SBU_{1}-PadA8)")
			(pinfunction "SBU_{1}")
			(pintype "bidirectional+no_connect")
		)
		(pad "A9" smd rect
			(at 1.1375 -2.525 180)
			(size 0.25 1.625)
			(layers "F.Cu" "F.Mask" "F.Paste")
			(net 71 "/USB Hub/USBC3_VBUS")
			(pinfunction "VBUS")
			(pintype "passive")
		)
		(pad "A10" smd rect
			(at 1.1375 -2.025 180)
			(size 0.25 1.625)
			(layers "F.Cu" "F.Mask" "F.Paste")
			(net 512 "/USB Hub/USBC3_RX_{2}+")
			(pinfunction "RX_{2}-")
			(pintype "bidirectional")
		)
		(pad "A11" smd rect
			(at 1.1375 -1.525 180)
			(size 0.25 1.625)
			(layers "F.Cu" "F.Mask" "F.Paste")
			(net 511 "/USB Hub/USBC3_RX_{2}-")
			(pinfunction "RX_{2}+")
			(pintype "bidirectional")
		)
		(pad "A12" smd rect
			(at 1.1375 -1.025 180)
			(size 0.25 1.625)
			(layers "F.Cu" "F.Mask" "F.Paste")
			(net 1 "GND")
			(pinfunction "GND")
			(pintype "passive")
		)
		(pad "B1" smd rect
			(at -1.1375 -1.025 180)
			(size 0.25 1.625)
			(layers "F.Cu" "F.Mask" "F.Paste")
			(net 1 "GND")
			(pinfunction "GND")
			(pintype "passive")
		)
		(pad "B2" smd rect
			(at -1.1375 -1.525 180)
			(size 0.25 1.625)
			(layers "F.Cu" "F.Mask" "F.Paste")
			(net 103 "/USB Hub/USBC3_CONN_TX2_N")
			(pinfunction "TX_{2}+")
			(pintype "bidirectional")
		)
		(pad "B3" smd rect
			(at -1.1375 -2.025 180)
			(size 0.25 1.625)
			(layers "F.Cu" "F.Mask" "F.Paste")
			(net 174 "/USB Hub/USBC3_CONN_TX2_P")
			(pinfunction "TX_{2}-")
			(pintype "bidirectional")
		)
		(pad "B4" smd rect
			(at -1.1375 -2.525 180)
			(size 0.25 1.625)
			(layers "F.Cu" "F.Mask" "F.Paste")
			(net 71 "/USB Hub/USBC3_VBUS")
			(pinfunction "VBUS")
			(pintype "passive")
		)
		(pad "B5" smd rect
			(at -1.1375 -3.025 180)
			(size 0.25 1.625)
			(layers "F.Cu" "F.Mask" "F.Paste")
			(net 509 "/USB Hub/USBC3_CC_{2}")
			(pinfunction "CC_{2}")
			(pintype "bidirectional")
		)
		(pad "B6" smd rect
			(at -1.1375 -3.525 180)
			(size 0.25 1.625)
			(layers "F.Cu" "F.Mask" "F.Paste")
			(net 506 "/USB Hub/USBC3_D+")
			(pinfunction "D_{B}+")
			(pintype "bidirectional")
		)
		(pad "B7" smd rect
			(at -1.1375 -4.025 180)
			(size 0.25 1.625)
			(layers "F.Cu" "F.Mask" "F.Paste")
			(net 508 "/USB Hub/USBC3_D-")
			(pinfunction "D_{B}-")
			(pintype "bidirectional")
		)
		(pad "B8" smd rect
			(at -1.1375 -4.525 180)
			(size 0.25 1.625)
			(layers "F.Cu" "F.Mask" "F.Paste")
			(net 178 "unconnected-(J6-SBU_{2}-PadB8)")
			(pinfunction "SBU_{2}")
			(pintype "bidirectional+no_connect")
		)
		(pad "B9" smd rect
			(at -1.1375 -5.025 180)
			(size 0.25 1.625)
			(layers "F.Cu" "F.Mask" "F.Paste")
			(net 71 "/USB Hub/USBC3_VBUS")
			(pinfunction "VBUS")
			(pintype "passive")
		)
		(pad "B10" smd rect
			(at -1.1375 -5.525 180)
			(size 0.25 1.625)
			(layers "F.Cu" "F.Mask" "F.Paste")
			(net 513 "/USB Hub/USBC3_RX_{1}+")
			(pinfunction "RX_{1}-")
			(pintype "bidirectional")
		)
		(pad "B11" smd rect
			(at -1.1375 -6.025 180)
			(size 0.25 1.625)
			(layers "F.Cu" "F.Mask" "F.Paste")
			(net 507 "/USB Hub/USBC3_RX_{1}-")
			(pinfunction "RX_{1}+")
			(pintype "bidirectional")
		)
		(pad "B12" smd rect
			(at -1.1375 -6.525 180)
			(size 0.25 1.625)
			(layers "F.Cu" "F.Mask" "F.Paste")
			(net 1 "GND")
			(pinfunction "GND")
			(pintype "passive")
		)
		(pad "SH" thru_hole oval
			(at -3 -7.849 90)
			(size 1 2.05)
			(drill oval 0.6 1.65)
			(layers "*.Cu" "*.Mask")
			(remove_unused_layers no)
			(net 1 "GND")
			(pinfunction "SH")
			(pintype "passive")
		)
		(pad "SH" thru_hole oval
			(at -3 0.25 90)
			(size 1 2.05)
			(drill oval 0.6 1.65)
			(layers "*.Cu" "*.Mask")
			(remove_unused_layers no)
			(net 1 "GND")
			(pinfunction "SH")
			(pintype "passive")
		)
		(pad "SH" thru_hole oval
			(at 3 -7.849 90)
			(size 1 2.05)
			(drill oval 0.6 1.65)
			(layers "*.Cu" "*.Mask")
			(remove_unused_layers no)
			(net 1 "GND")
			(pinfunction "SH")
			(pintype "passive")
		)
		(pad "SH" thru_hole oval
			(at 3 0.25 90)
			(size 1 2.05)
			(drill oval 0.6 1.65)
			(layers "*.Cu" "*.Mask")
			(remove_unused_layers no)
			(net 1 "GND")
			(pinfunction "SH")
			(pintype "passive")
		)
	)
	(footprint "antmicro-footprints:C_0402_1005Metric"
		(layer "F.Cu")
		(at 204.965 117.88 -90)
		(descr "Capacitor SMD 0402")
		(tags "capacitor SMD 0402")
		(property "Reference" "C100"
			(at -3.68 0.465 90)
			(layer "F.SilkS")
			(effects
				(font
					(size 0.7 0.7)
					(thickness 0.15)
				)
				(justify right top)
			)
		)
		(property "Value" "C_100n_0402"
			(at -1.022927 2.155213 90)
			(layer "F.Fab")
			(effects
				(font
					(size 0.7 0.7)
					(thickness 0.15)
				)
				(justify right top)
			)
		)
		(property "Datasheet" "https://www.murata.com/products/productdetail?partno=GRM155R61H104KE14%23"
			(at 0 0 90)
			(layer "F.Fab")
			(hide yes)
			(effects
				(font
					(size 1.27 1.27)
					(thickness 0.15)
				)
			)
		)
		(property "Description" "SMD Multilayer Ceramic Capacitor, 0.1 µF, 50 V, 0402 [1005 Metric], ± 10%, X5R, GRM Series"
			(at 0 0 90)
			(layer "F.Fab")
			(hide yes)
			(effects
				(font
					(size 1.27 1.27)
					(thickness 0.15)
				)
			)
		)
		(property "MPN" "GRM155R61H104KE14D"
			(at 0 0 270)
			(unlocked yes)
			(layer "F.Fab")
			(hide yes)
			(effects
				(font
					(size 1 1)
					(thickness 0.15)
				)
			)
		)
		(property "Val" "100n"
			(at 0 0 270)
			(unlocked yes)
			(layer "F.Fab")
			(hide yes)
			(effects
				(font
					(size 1 1)
					(thickness 0.15)
				)
			)
		)
		(property "Voltage" "50V"
			(at 0 0 270)
			(unlocked yes)
			(layer "F.Fab")
			(hide yes)
			(effects
				(font
					(size 1 1)
					(thickness 0.15)
				)
			)
		)
		(property "Dielectric" "X5R"
			(at 0 0 270)
			(unlocked yes)
			(layer "F.Fab")
			(hide yes)
			(effects
				(font
					(size 1 1)
					(thickness 0.15)
				)
			)
		)
		(property "Manufacturer" "Murata"
			(at 0 0 270)
			(unlocked yes)
			(layer "F.Fab")
			(hide yes)
			(effects
				(font
					(size 1 1)
					(thickness 0.15)
				)
			)
		)
		(property "License" "Apache-2.0"
			(at 0 0 270)
			(unlocked yes)
			(layer "F.Fab")
			(hide yes)
			(effects
				(font
					(size 1 1)
					(thickness 0.15)
				)
			)
		)
		(property "Author" "Antmicro"
			(at 0 0 270)
			(unlocked yes)
			(layer "F.Fab")
			(hide yes)
			(effects
				(font
					(size 1 1)
					(thickness 0.15)
				)
			)
		)
		(sheetname "/USB Hub/")
		(sheetfile "usb_hub.kicad_sch")
		(attr smd)
		(fp_poly
			(pts
				(xy -0.925 -0.47) (xy -0.925 0.47) (xy 0.925 0.47) (xy 0.925 -0.47)
			)
			(stroke
				(width 0.05)
				(type default)
			)
			(fill no)
			(layer "F.CrtYd")
		)
		(fp_line
			(start -0.494 0.248)
			(end -0.494 -0.25)
			(stroke
				(width 0.15)
				(type solid)
			)
			(layer "F.Fab")
		)
		(fp_line
			(start 0.504 0.248)
			(end -0.494 0.248)
			(stroke
				(width 0.15)
				(type solid)
			)
			(layer "F.Fab")
		)
		(fp_line
			(start -0.494 -0.25)
			(end 0.504 -0.25)
			(stroke
				(width 0.15)
				(type solid)
			)
			(layer "F.Fab")
		)
		(fp_line
			(start 0.504 -0.25)
			(end 0.504 0.248)
			(stroke
				(width 0.15)
				(type solid)
			)
			(layer "F.Fab")
		)
		(fp_text user "License: Apache-2.0"
			(at -0.939 5.799 90)
			(layer "F.Fab")
			(effects
				(font
					(size 0.7 0.7)
					(thickness 0.15)
				)
				(justify right top)
			)
		)
		(fp_text user "Author: Antmicro"
			(at -0.939 3.399 90)
			(layer "F.Fab")
			(effects
				(font
					(size 0.7 0.7)
					(thickness 0.15)
				)
				(justify right top)
			)
		)
		(fp_text user "${REFERENCE}"
			(at -0.939 4.599 90)
			(layer "F.Fab")
			(effects
				(font
					(size 0.7 0.7)
					(thickness 0.15)
				)
				(justify right top)
			)
		)
		(pad "1" smd roundrect
			(at -0.48 0 270)
			(size 0.59 0.64)
			(layers "F.Cu" "F.Mask" "F.Paste")
			(roundrect_rratio 0.25)
			(net 1 "GND")
			(pintype "passive")
		)
		(pad "2" smd roundrect
			(at 0.48 0 270)
			(size 0.59 0.64)
			(layers "F.Cu" "F.Mask" "F.Paste")
			(roundrect_rratio 0.25)
			(net 282 "+1V15")
			(pintype "passive")
		)
	)
)
